(kicad_pcb
	(version 20260206)
	(generator "pcbnew")
	(generator_version "10.0")
	(general
		(thickness 1.6)
		(legacy_teardrops no)
	)
	(paper "A4")
	(title_block
		(title "12092022_DA0F0TFB6D0_F0T_FAN_BOARD_MP5048_D_brd_v02_OCP.brd")
		(comment 1 "Grand Teton / footprints 770-771 of 924")
	)
	(layers
		(0 "F.Cu" signal "TOP")
		(4 "In1.Cu" signal "GND")
		(6 "In2.Cu" signal "IN1")
		(8 "In3.Cu" signal "IN2")
		(10 "In4.Cu" signal "GND1")
		(2 "B.Cu" signal "BOTTOM")
		(9 "F.Adhes" user "F.Adhesive")
		(11 "B.Adhes" user "B.Adhesive")
		(13 "F.Paste" user "Package Geometry/Pastemask Top")
		(15 "B.Paste" user "Package Geometry/Pastemask Bottom")
		(5 "F.SilkS" user "Ref Des/Silkscreen Top")
		(7 "B.SilkS" user "Ref Des/Silkscreen Bottom")
		(1 "F.Mask" user "Board Geometry/Soldermask Top")
		(3 "B.Mask" user "Board Geometry/Soldermask Bottom")
		(17 "Dwgs.User" user "User.Drawings")
		(19 "Cmts.User" user "User.Comments")
		(21 "Eco1.User" user "User.Eco1")
		(23 "Eco2.User" user "User.Eco2")
		(25 "Edge.Cuts" user "Board Geometry/Outline")
		(27 "Margin" user)
		(31 "F.CrtYd" user "Package Geometry/Place Bound Top")
		(29 "B.CrtYd" user "Package Geometry/Place Bound Bottom")
		(35 "F.Fab" user "Ref Des/Assembly Top")
		(33 "B.Fab" user "Ref Des/Assembly Bottom")
	)
	(footprint ""
		(layer "B.Cu")
		(at 6.700012 -289.310064 180)
		(property "Reference" "J8"
			(at 2.001012 19.273266 0)
			(unlocked yes)
			(layer "B.SilkS")
			(effects
				(font
					(size 0.7874 0.5842)
					(thickness 0.1524)
				)
				(justify left mirror)
			)
		)
		(property "Value" ""
			(at 0 0 0)
			(layer "B.Fab")
			(effects
				(font
					(size 1.27 1.27)
				)
				(justify mirror)
			)
		)
		(duplicate_pad_numbers_are_jumpers no)
		(fp_line
			(start 4.350004 18.524982)
			(end -6.35 18.524982)
			(stroke
				(width 0.1524)
				(type default)
			)
			(layer "B.SilkS")
		)
		(fp_line
			(start 4.350004 -4.52501)
			(end 4.350004 18.524982)
			(stroke
				(width 0.1524)
				(type default)
			)
			(layer "B.SilkS")
		)
		(fp_line
			(start 1.249934 15.424912)
			(end -3.24993 15.424912)
			(stroke
				(width 0.1524)
				(type default)
			)
			(layer "B.SilkS")
		)
		(fp_line
			(start 1.249934 8.200136)
			(end 4.350004 8.200136)
			(stroke
				(width 0.1524)
				(type default)
			)
			(layer "B.SilkS")
		)
		(fp_line
			(start 1.249934 8.200136)
			(end 1.249934 15.424912)
			(stroke
				(width 0.1524)
				(type default)
			)
			(layer "B.SilkS")
		)
		(fp_line
			(start 1.249934 5.799836)
			(end 4.350004 5.799836)
			(stroke
				(width 0.1524)
				(type default)
			)
			(layer "B.SilkS")
		)
		(fp_line
			(start 1.249934 -1.42494)
			(end 1.249934 5.799836)
			(stroke
				(width 0.1524)
				(type default)
			)
			(layer "B.SilkS")
		)
		(fp_line
			(start -0.029972 -1.42494)
			(end 1.249934 -1.42494)
			(stroke
				(width 0.1524)
				(type default)
			)
			(layer "B.SilkS")
		)
		(fp_line
			(start -3.24993 15.424912)
			(end -3.24993 -1.42494)
			(stroke
				(width 0.1524)
				(type default)
			)
			(layer "B.SilkS")
		)
		(fp_line
			(start -3.24993 -1.42494)
			(end -1.96977 -1.42494)
			(stroke
				(width 0.1524)
				(type default)
			)
			(layer "B.SilkS")
		)
		(fp_line
			(start -6.35 18.524982)
			(end -6.35 -4.52501)
			(stroke
				(width 0.1524)
				(type default)
			)
			(layer "B.SilkS")
		)
		(fp_line
			(start -6.35 -4.52501)
			(end 4.350004 -4.52501)
			(stroke
				(width 0.1524)
				(type default)
			)
			(layer "B.SilkS")
		)
		(fp_poly
			(pts
				(xy 5.527802 -0.508) (xy 5.527802 0.508) (xy 4.511802 0)
			)
			(stroke
				(width 0)
				(type default)
			)
			(fill yes)
			(layer "B.SilkS")
		)
		(fp_line
			(start 4.350004 18.524982)
			(end -6.35 18.524982)
			(stroke
				(width 0.1)
				(type default)
			)
			(layer "B.Fab")
		)
		(fp_line
			(start 4.350004 -4.52501)
			(end 4.350004 18.524982)
			(stroke
				(width 0.1)
				(type default)
			)
			(layer "B.Fab")
		)
		(fp_line
			(start -6.35 18.524982)
			(end -6.35 -4.52501)
			(stroke
				(width 0.1)
				(type default)
			)
			(layer "B.Fab")
		)
		(fp_line
			(start -6.35 -4.52501)
			(end 4.350004 -4.52501)
			(stroke
				(width 0.1)
				(type default)
			)
			(layer "B.Fab")
		)
		(fp_poly
			(pts
				(xy 5.527802 -0.508) (xy 5.527802 0.508) (xy 4.511802 0)
			)
			(stroke
				(width 0)
				(type default)
			)
			(fill yes)
			(layer "B.Fab")
		)
		(pad "" np_thru_hole circle
			(at -0.999998 -1.89992 90)
			(size 1.4986 1.4986)
			(drill 1.4986)
			(layers "*.Cu" "*.Mask")
			(clearance 0.381)
			(thermal_gap 0.381)
		)
		(pad "1" thru_hole rect
			(at 0 0 90)
			(size 1.3716 1.3716)
			(drill 0.9652)
			(layers "*.Cu" "*.Mask")
			(remove_unused_layers no)
			(net "FAN_7_TACH_IL_D")
			(clearance 0.0508)
			(padstack
				(mode front_inner_back)
				(layer "Inner"
					(shape circle)
					(size 1.3716 1.3716)
					(clearance 0.0508)
				)
				(layer "B.Cu"
					(shape rect)
					(size 1.3716 1.3716)
					(thermal_gap 0.0508)
					(clearance 0.0508)
				)
			)
		)
		(pad "2" thru_hole circle
			(at -1.999996 0 90)
			(size 1.3716 1.3716)
			(drill 0.9652)
			(layers "*.Cu" "*.Mask")
			(remove_unused_layers no)
			(net "FAN_7_PWM_OL_R")
			(clearance 0.0508)
			(thermal_gap 0.0508)
		)
		(pad "3" thru_hole circle
			(at 0 1.999996 90)
			(size 1.3716 1.3716)
			(drill 0.9652)
			(layers "*.Cu" "*.Mask")
			(remove_unused_layers no)
			(net "FAN_7_PWM_IL_R")
			(clearance 0.0508)
			(thermal_gap 0.0508)
		)
		(pad "4" thru_hole circle
			(at -1.999996 1.999996 90)
			(size 1.3716 1.3716)
			(drill 0.9652)
			(layers "*.Cu" "*.Mask")
			(remove_unused_layers no)
			(net "FAN_7_PRESENT_R_N")
			(clearance 0.0508)
			(thermal_gap 0.0508)
		)
		(pad "5" thru_hole circle
			(at 0 3.999992 90)
			(size 1.3716 1.3716)
			(drill 0.9652)
			(layers "*.Cu" "*.Mask")
			(remove_unused_layers no)
			(net "P12V_LED_R1_FAN7")
			(clearance 0.0508)
			(thermal_gap 0.0508)
		)
		(pad "6" thru_hole circle
			(at -1.999996 3.999992 90)
			(size 1.3716 1.3716)
			(drill 0.9652)
			(layers "*.Cu" "*.Mask")
			(remove_unused_layers no)
			(net "SMB_FAN7_SCL_R")
			(clearance 0.0508)
			(thermal_gap 0.0508)
		)
		(pad "7" thru_hole circle
			(at 0 5.999988 90)
			(size 1.3716 1.3716)
			(drill 0.9652)
			(layers "*.Cu" "*.Mask")
			(remove_unused_layers no)
			(net "SMB_FAN7_SDA_R")
			(clearance 0.0508)
			(thermal_gap 0.0508)
		)
		(pad "8" thru_hole circle
			(at -1.999996 5.999988 90)
			(size 1.3716 1.3716)
			(drill 0.9652)
			(layers "*.Cu" "*.Mask")
			(remove_unused_layers no)
			(net "GND")
			(clearance 0.0508)
			(thermal_gap 0.0508)
		)
		(pad "9" thru_hole circle
			(at 0 7.999984 90)
			(size 1.3716 1.3716)
			(drill 0.9652)
			(layers "*.Cu" "*.Mask")
			(remove_unused_layers no)
			(net "GND")
			(clearance 0.0508)
			(thermal_gap 0.0508)
		)
		(pad "10" thru_hole circle
			(at -1.999996 7.999984 90)
			(size 1.3716 1.3716)
			(drill 0.9652)
			(layers "*.Cu" "*.Mask")
			(remove_unused_layers no)
			(net "P52V_FAN_7")
			(clearance 0.0508)
			(thermal_gap 0.0508)
		)
		(pad "11" thru_hole circle
			(at 0 9.99998 90)
			(size 1.3716 1.3716)
			(drill 0.9652)
			(layers "*.Cu" "*.Mask")
			(remove_unused_layers no)
			(net "P52V_FAN_7")
			(clearance 0.0508)
			(thermal_gap 0.0508)
		)
		(pad "12" thru_hole circle
			(at -1.999996 9.99998 90)
			(size 1.3716 1.3716)
			(drill 0.9652)
			(layers "*.Cu" "*.Mask")
			(remove_unused_layers no)
			(net "FAN_7_FAIL_R_LED_N")
			(clearance 0.0508)
			(thermal_gap 0.0508)
		)
		(pad "13" thru_hole circle
			(at 0 11.999976 90)
			(size 1.3716 1.3716)
			(drill 0.9652)
			(layers "*.Cu" "*.Mask")
			(remove_unused_layers no)
			(net "FAN_7_TACH_OL_D")
			(clearance 0.0508)
			(thermal_gap 0.0508)
		)
		(pad "14" thru_hole circle
			(at -1.999996 11.999976 90)
			(size 1.3716 1.3716)
			(drill 0.9652)
			(layers "*.Cu" "*.Mask")
			(remove_unused_layers no)
			(net "FAN_7_OK_R_LED_N")
			(clearance 0.0508)
			(thermal_gap 0.0508)
		)
		(pad "15" thru_hole circle
			(at 0 13.999972 90)
			(size 1.3716 1.3716)
			(drill 0.9652)
			(layers "*.Cu" "*.Mask")
			(remove_unused_layers no)
			(net "Net_597")
			(clearance 0.0508)
			(thermal_gap 0.0508)
		)
		(pad "16" thru_hole circle
			(at -1.999996 13.999972 90)
			(size 1.3716 1.3716)
			(drill 0.9652)
			(layers "*.Cu" "*.Mask")
			(remove_unused_layers no)
			(net "Net_596")
			(clearance 0.0508)
			(thermal_gap 0.0508)
		)
		(zone
			(layers "F.Cu" "B.Cu" "In1.Cu" "In2.Cu" "In3.Cu" "In4.Cu")
			(hatch none 0.5)
			(connect_pads
				(clearance 0)
			)
			(min_thickness 0.25)
			(keepout
				(tracks not_allowed)
				(vias allowed)
				(pads allowed)
				(copperpour not_allowed)
				(footprints allowed)
			)
			(placement
				(enabled no)
				(sheetname "")
			)
			(fill
				(thermal_gap 0.5)
				(thermal_bridge_width 0.5)
				(island_removal_mode 0)
			)
			(polygon
				(pts
					(arc
						(start 8.95731 -287.410144)
						(mid 6.44271 -287.410144)
						(end 8.95731 -287.410144)
					)
				)
			)
		)
	)
	(footprint ""
		(layer "B.Cu")
		(at 6.700012 -12.409932 180)
		(property "Reference" "J5"
			(at 2.763012 19.186398 0)
			(unlocked yes)
			(layer "B.SilkS")
			(effects
				(font
					(size 0.7874 0.5842)
					(thickness 0.1524)
				)
				(justify left mirror)
			)
		)
		(property "Value" ""
			(at 0 0 0)
			(layer "B.Fab")
			(effects
				(font
					(size 1.27 1.27)
				)
				(justify mirror)
			)
		)
		(duplicate_pad_numbers_are_jumpers no)
		(fp_line
			(start 4.350004 18.524982)
			(end -6.35 18.524982)
			(stroke
				(width 0.1524)
				(type default)
			)
			(layer "B.SilkS")
		)
		(fp_line
			(start 4.350004 -4.52501)
			(end 4.350004 18.524982)
			(stroke
				(width 0.1524)
				(type default)
			)
			(layer "B.SilkS")
		)
		(fp_line
			(start 1.249934 15.424912)
			(end -3.24993 15.424912)
			(stroke
				(width 0.1524)
				(type default)
			)
			(layer "B.SilkS")
		)
		(fp_line
			(start 1.249934 8.200136)
			(end 4.350004 8.200136)
			(stroke
				(width 0.1524)
				(type default)
			)
			(layer "B.SilkS")
		)
		(fp_line
			(start 1.249934 8.200136)
			(end 1.249934 15.424912)
			(stroke
				(width 0.1524)
				(type default)
			)
			(layer "B.SilkS")
		)
		(fp_line
			(start 1.249934 5.799836)
			(end 4.350004 5.799836)
			(stroke
				(width 0.1524)
				(type default)
			)
			(layer "B.SilkS")
		)
		(fp_line
			(start 1.249934 -1.42494)
			(end 1.249934 5.799836)
			(stroke
				(width 0.1524)
				(type default)
			)
			(layer "B.SilkS")
		)
		(fp_line
			(start -0.029972 -1.42494)
			(end 1.249934 -1.42494)
			(stroke
				(width 0.1524)
				(type default)
			)
			(layer "B.SilkS")
		)
		(fp_line
			(start -3.24993 15.424912)
			(end -3.24993 -1.42494)
			(stroke
				(width 0.1524)
				(type default)
			)
			(layer "B.SilkS")
		)
		(fp_line
			(start -3.24993 -1.42494)
			(end -1.96977 -1.42494)
			(stroke
				(width 0.1524)
				(type default)
			)
			(layer "B.SilkS")
		)
		(fp_line
			(start -6.35 18.524982)
			(end -6.35 -4.52501)
			(stroke
				(width 0.1524)
				(type default)
			)
			(layer "B.SilkS")
		)
		(fp_line
			(start -6.35 -4.52501)
			(end 4.350004 -4.52501)
			(stroke
				(width 0.1524)
				(type default)
			)
			(layer "B.SilkS")
		)
		(fp_poly
			(pts
				(xy 5.527802 -0.508) (xy 5.527802 0.508) (xy 4.511802 0)
			)
			(stroke
				(width 0)
				(type default)
			)
			(fill yes)
			(layer "B.SilkS")
		)
		(fp_line
			(start 4.350004 18.524982)
			(end -6.35 18.524982)
			(stroke
				(width 0.1)
				(type default)
			)
			(layer "B.Fab")
		)
		(fp_line
			(start 4.350004 -4.52501)
			(end 4.350004 18.524982)
			(stroke
				(width 0.1)
				(type default)
			)
			(layer "B.Fab")
		)
		(fp_line
			(start -6.35 18.524982)
			(end -6.35 -4.52501)
			(stroke
				(width 0.1)
				(type default)
			)
			(layer "B.Fab")
		)
		(fp_line
			(start -6.35 -4.52501)
			(end 4.350004 -4.52501)
			(stroke
				(width 0.1)
				(type default)
			)
			(layer "B.Fab")
		)
		(fp_poly
			(pts
				(xy 5.527802 -0.508) (xy 5.527802 0.508) (xy 4.511802 0)
			)
			(stroke
				(width 0)
				(type default)
			)
			(fill yes)
			(layer "B.Fab")
		)
		(pad "" np_thru_hole circle
			(at -0.999998 -1.89992 90)
			(size 1.4986 1.4986)
			(drill 1.4986)
			(layers "*.Cu" "*.Mask")
			(clearance 0.381)
			(thermal_gap 0.381)
		)
		(pad "1" thru_hole rect
			(at 0 0 90)
			(size 1.3716 1.3716)
			(drill 0.9652)
			(layers "*.Cu" "*.Mask")
			(remove_unused_layers no)
			(net "FAN_4_TACH_IL_D")
			(clearance 0.0508)
			(padstack
				(mode front_inner_back)
				(layer "Inner"
					(shape circle)
					(size 1.3716 1.3716)
					(clearance 0.0508)
				)
				(layer "B.Cu"
					(shape rect)
					(size 1.3716 1.3716)
					(thermal_gap 0.0508)
					(clearance 0.0508)
				)
			)
		)
		(pad "2" thru_hole circle
			(at -1.999996 0 90)
			(size 1.3716 1.3716)
			(drill 0.9652)
			(layers "*.Cu" "*.Mask")
			(remove_unused_layers no)
			(net "FAN_4_PWM_OL_R")
			(clearance 0.0508)
			(thermal_gap 0.0508)
		)
		(pad "3" thru_hole circle
			(at 0 1.999996 90)
			(size 1.3716 1.3716)
			(drill 0.9652)
			(layers "*.Cu" "*.Mask")
			(remove_unused_layers no)
			(net "FAN_4_PWM_IL_R")
			(clearance 0.0508)
			(thermal_gap 0.0508)
		)
		(pad "4" thru_hole circle
			(at -1.999996 1.999996 90)
			(size 1.3716 1.3716)
			(drill 0.9652)
			(layers "*.Cu" "*.Mask")
			(remove_unused_layers no)
			(net "FAN_4_PRESENT_R_N")
			(clearance 0.0508)
			(thermal_gap 0.0508)
		)
		(pad "5" thru_hole circle
			(at 0 3.999992 90)
			(size 1.3716 1.3716)
			(drill 0.9652)
			(layers "*.Cu" "*.Mask")
			(remove_unused_layers no)
			(net "P12V_LED_R1_FAN4")
			(clearance 0.0508)
			(thermal_gap 0.0508)
		)
		(pad "6" thru_hole circle
			(at -1.999996 3.999992 90)
			(size 1.3716 1.3716)
			(drill 0.9652)
			(layers "*.Cu" "*.Mask")
			(remove_unused_layers no)
			(net "SMB_FAN4_SCL_R")
			(clearance 0.0508)
			(thermal_gap 0.0508)
		)
		(pad "7" thru_hole circle
			(at 0 5.999988 90)
			(size 1.3716 1.3716)
			(drill 0.9652)
			(layers "*.Cu" "*.Mask")
			(remove_unused_layers no)
			(net "SMB_FAN4_SDA_R")
			(clearance 0.0508)
			(thermal_gap 0.0508)
		)
		(pad "8" thru_hole circle
			(at -1.999996 5.999988 90)
			(size 1.3716 1.3716)
			(drill 0.9652)
			(layers "*.Cu" "*.Mask")
			(remove_unused_layers no)
			(net "GND")
			(clearance 0.0508)
			(thermal_gap 0.0508)
		)
		(pad "9" thru_hole circle
			(at 0 7.999984 90)
			(size 1.3716 1.3716)
			(drill 0.9652)
			(layers "*.Cu" "*.Mask")
			(remove_unused_layers no)
			(net "GND")
			(clearance 0.0508)
			(thermal_gap 0.0508)
		)
		(pad "10" thru_hole circle
			(at -1.999996 7.999984 90)
			(size 1.3716 1.3716)
			(drill 0.9652)
			(layers "*.Cu" "*.Mask")
			(remove_unused_layers no)
			(net "P52V_FAN_4")
			(clearance 0.0508)
			(thermal_gap 0.0508)
		)
		(pad "11" thru_hole circle
			(at 0 9.99998 90)
			(size 1.3716 1.3716)
			(drill 0.9652)
			(layers "*.Cu" "*.Mask")
			(remove_unused_layers no)
			(net "P52V_FAN_4")
			(clearance 0.0508)
			(thermal_gap 0.0508)
		)
		(pad "12" thru_hole circle
			(at -1.999996 9.99998 90)
			(size 1.3716 1.3716)
			(drill 0.9652)
			(layers "*.Cu" "*.Mask")
			(remove_unused_layers no)
			(net "FAN_4_FAIL_R_LED_N")
			(clearance 0.0508)
			(thermal_gap 0.0508)
		)
		(pad "13" thru_hole circle
			(at 0 11.999976 90)
			(size 1.3716 1.3716)
			(drill 0.9652)
			(layers "*.Cu" "*.Mask")
			(remove_unused_layers no)
			(net "FAN_4_TACH_OL_D")
			(clearance 0.0508)
			(thermal_gap 0.0508)
		)
		(pad "14" thru_hole circle
			(at -1.999996 11.999976 90)
			(size 1.3716 1.3716)
			(drill 0.9652)
			(layers "*.Cu" "*.Mask")
			(remove_unused_layers no)
			(net "FAN_4_OK_R_LED_N")
			(clearance 0.0508)
			(thermal_gap 0.0508)
		)
		(pad "15" thru_hole circle
			(at 0 13.999972 90)
			(size 1.3716 1.3716)
			(drill 0.9652)
			(layers "*.Cu" "*.Mask")
			(remove_unused_layers no)
			(net "Net_606")
			(clearance 0.0508)
			(thermal_gap 0.0508)
		)
		(pad "16" thru_hole circle
			(at -1.999996 13.999972 90)
			(size 1.3716 1.3716)
			(drill 0.9652)
			(layers "*.Cu" "*.Mask")
			(remove_unused_layers no)
			(net "Net_605")
			(clearance 0.0508)
			(thermal_gap 0.0508)
		)
		(zone
			(layers "F.Cu" "B.Cu" "In1.Cu" "In2.Cu" "In3.Cu" "In4.Cu")
			(hatch none 0.5)
			(connect_pads
				(clearance 0)
			)
			(min_thickness 0.25)
			(keepout
				(tracks not_allowed)
				(vias allowed)
				(pads allowed)
				(copperpour not_allowed)
				(footprints allowed)
			)
			(placement
				(enabled no)
				(sheetname "")
			)
			(fill
				(thermal_gap 0.5)
				(thermal_bridge_width 0.5)
				(island_removal_mode 0)
			)
			(polygon
				(pts
					(arc
						(start 8.95731 -10.510012)
						(mid 6.44271 -10.510012)
						(end 8.95731 -10.510012)
					)
				)
			)
		)
	)
)
